FILE_TYPE = CONNECTIVITY;
{Allegro Design Entry HDL 17.4-2019 S026 (4007227) 1/17/2022}
"PAGE_NUMBER" = 340;
0"NC";
1"GND\g";
2"GND\g";
3"GND\g";
4"GND\g";
5"GND\g";
6"P3V3_AUX\g";
7"P3V3_AUX\g";
8"GND\g";
9"P3V3_AUX\g";
10"GND\g";
11"P3V3_AUX\g";
12"P3V3_AUX\g";
13"GND\g";
14"P3V3_AUX\g";
15"GND\g";
16"GND\g";
17"GND\g";
18"P3V3_OCP_SFF_R\g";
19"GND\g";
20"GND\g";
21"OCP_V3_1_P3V3_R3_PWRGD";
22"OCP_SFF_AUX_PWR_EN_R3";
23"FM_PLD_OCP_SFF_AUX_PWR_EN";
24"HP_LVC3_OCP_V3_1_PWRGD_R1";
25"OCP_V3_1_P3V3_PWRGD";
26"RST_PERST_OCP_SFF_BUF_N";
27"P3V3_AUX\g";
28"RST_PERST_OCP_SFF_N";
29"RST_PERST_OCP_SFF_BUF_R_N";
30"HP_LVC3_OCP_V3_1_PWRGD";
31"HP_LVC3_OCP_V3_1_PWRGD_R2";
32"OCP_V3_1_P3V3_PWRGD";
33"OCP_V3_1_P3V3_PWRGD";
34"OCP_V3_1_P3V3_PWRGD";
35"P12V_OCP_SFF_EN_R";
36"HP_LVC3_OCP_SFF_PRSNT2";
37"HP_LVC3_OCP_SFF_PRSNT2_N";
38"HP_LVC3_OCP_V3_1_P12V_R2_PWRGD";
39"HP_LVC3_OCP_V3_1_P12V_PWRGD";
40"RST_PERST_OCP_SFF_R_N";
41"P12V_OCP_SFF_BUF_EN_R";
42"P12V_OCP_SFF_BUF_EN";
43"OCP_V3_1_P3V3_PLD_PWRGD";
44"OCP_V3_1_P3V3_PLD_R_PWRGD";
45"OCP_SFF_AUX_PWR_EN";
46"OCP_V3_1_P3V3_R2_PWRGD";
47"OCP_V3_1_P3V3_R1_PWRGD";
48"P3V3_AUX\g";
49"GND\g";
50"P3V3_AUX\g";
51"P3V3_AUX\g";
52"GND\g";
53"GND\g";
54"P3V3_AUX\g";
55"P3V3_OCP_SFF_R\g";
56"P3V3_AUX\g";
57"P12V_OCP_V3_1_PLD_PWRGD";
58"HP_LVC3_OCP_V3_1_P12V_R_PWRGD";
59"P12V_OCP_V3_1_PLD_R_PWRGD";
60"P12V_OCP_SFF_EN_R3";
61"HP_LVC3_OCP_V3_1_P12V_PWRGD";
62"HP_LVC3_OCP_V3_1_P12V_R2_PWRGD";
%"Q_RES"
"1","(-1950,6600)","2","pure_quanta","I101";
;
LOCATION"R1519"
$SEC"1"
CDS_SEC"1"
MATERIAL"EMPTY"
VALUE"0"
WATTAGE"1/16W"
TOLERANCE"5%"
PACK_TYPE"0402LF"
CDS_LIB"pure_quanta"
PART_NUMBER"CS00002JB13";
"B"
$PN"2"32;
"A"
$PN"1"21;
%"Q_RES"
"1","(-2000,6325)","0","pure_quanta","I102";
;
LOCATION"R1518"
$SEC"1"
CDS_SEC"1"
WATTAGE"1/16W"
PACK_TYPE"0402LF"
TOLERANCE"5%"
VALUE"0"
MATERIAL"CHIP"
CDS_LIB"pure_quanta"
PART_NUMBER"CS00002JB13";
"B"
$PN"2"21;
"A"
$PN"1"31;
%"Q_RES"
"1","(-1000,6600)","0","pure_quanta","I13";
;
LOCATION"R9022"
$SEC"1"
CDS_SEC"1"
VALUE"33.2"
MATERIAL"CHIP"
PACK_TYPE"0402LF"
WATTAGE"1/16W"
TOLERANCE"1%"
CDS_LIB"pure_quanta"
PART_NUMBER"CS03322FB03";
"B"
$PN"2"30;
"A"
$PN"1"21;
%"Q_RES"
"1","(-1000,6700)","0","pure_quanta","I14";
;
LOCATION"R9023"
$SEC"1"
CDS_SEC"1"
PACK_TYPE"0402LF"
MATERIAL"CHIP"
VALUE"33.2"
TOLERANCE"1%"
WATTAGE"1/16W"
CDS_LIB"pure_quanta"
PART_NUMBER"CS03322FB03";
"B"
$PN"2"40;
"A"
$PN"1"28;
%"Q_RES"
"1","(825,4575)","2","pure_quanta","I15";
;
LOCATION"R9030"
$SEC"1"
CDS_SEC"1"
MATERIAL"EMPTY"
VALUE"0"
CDS_LIB"pure_quanta"
BOM_COST"MEM"
WATTAGE"1/16W"
TOLERANCE"5%"
PACK_TYPE"0402LF"
PART_NUMBER"CS00002JB13";
"B"
$PN"2"23;
"A"
$PN"1"22;
%"UNIVERSAL_GND"
"1","(150,5100)","0","pure_quanta_power","I16";
;
CDS_LIB"pure_quanta_power"
HDL_POWER"GND";
"A"1;
%"Q_RES"
"1","(825,6075)","2","pure_quanta","I18";
;
LOCATION"R9029"
$SEC"1"
CDS_SEC"1"
VALUE"0"
MATERIAL"EMPTY"
PACK_TYPE"0402LF"
TOLERANCE"5%"
WATTAGE"1/16W"
BOM_COST"MEM"
CDS_LIB"pure_quanta"
PART_NUMBER"CS00002JB13";
"B"
$PN"2"24;
"A"
$PN"1"22;
%"UNIVERSAL_GND"
"1","(-50,5500)","0","pure_quanta_power","I19";
;
CDS_LIB"pure_quanta_power"
HDL_POWER"GND";
"A"2;
%"Q_RES"
"2","(-1625,5650)","2","pure_quanta","I2";
;
LOCATION"R9032"
$SEC"1"
CDS_SEC"1"
MATERIAL"CHIP"
WATTAGE"1/16W"
PACK_TYPE"0402LF"
VALUE"10K"
TOLERANCE"1%"
CDS_LIB"pure_quanta"
PART_NUMBER"CS31002FB08";
"A"
$PN"1"7;
"B"
$PN"2"23;
%"UNIVERSAL_POWER"
"1","(-25,5925)","2","pure_quanta_power","I21";
;
HDL_POWER"P3V3_AUX"
CDS_LIB"pure_quanta_power";
"A"27;
%"Q_RES"
"1","(1825,5375)","0","pure_quanta","I22";
;
LOCATION"R9031"
$SEC"1"
CDS_SEC"1"
PACK_TYPE"0402LF"
MATERIAL"CHIP"
VALUE"33.2"
CDS_LIB"pure_quanta"
TOLERANCE"1%"
WATTAGE"1/16W"
PART_NUMBER"CS03322FB03";
"B"
$PN"2"45;
"A"
$PN"1"22;
%"UNIVERSAL_GND"
"1","(150,6225)","0","pure_quanta_power","I24";
;
CDS_LIB"pure_quanta_power"
HDL_POWER"GND";
"A"3;
%"74LVC1G08W57"
"1","(500,6600)","0","pure_quanta","I25";
;
LOCATION"U9001"
$SEC"1"
CDS_SEC"1"
PART_TYPE"SMLF"
MATERIAL"IC"
VALUE"74LVC1G08W5-7"
NEEDS_NO_SIZE"TRUE"
CDS_LIB"pure_quanta"
CDS_LMAN_SYM_OUTLINE"-150,150,150,-150"
PART_NUMBER"AL1G0008020";
"VCC"
$PN"5"48;
"Y"
$PN"4"29;
"GND"
$PN"3"3;
"B"
$PN"2"30;
"A"
$PN"1"40;
%"UNIVERSAL_GND"
"1","(1050,6675)","0","pure_quanta_power","I26";
;
CDS_LIB"pure_quanta_power"
HDL_POWER"GND";
"A"4;
%"Q_CAP"
"1","(1050,6875)","0","pure_quanta","I27";
;
LOCATION"C9007"
$SEC"1"
CDS_SEC"1"
MATERIAL"X7R"
PACK_TYPE"0402"
TOLERANCE"10%"
VALUE"0.1UF"
VOLTAGE"25V"
CDS_LIB"pure_quanta"
PART_NUMBER"CH4104K1B00";
"B"
$PN"2"4;
"A"
$PN"1"48;
%"UNIVERSAL_POWER"
"1","(1050,7150)","2","pure_quanta_power","I28";
;
HDL_POWER"P3V3_AUX"
CDS_LIB"pure_quanta_power";
"A"48;
%"Q_RES"
"1","(2050,6550)","0","pure_quanta","I29";
;
LOCATION"R9033"
$SEC"1"
CDS_SEC"1"
MATERIAL"CHIP"
VALUE"33.2"
PACK_TYPE"0402LF"
WATTAGE"1/16W"
TOLERANCE"1%"
CDS_LIB"pure_quanta"
PART_NUMBER"CS03322FB03";
"B"
$PN"2"26;
"A"
$PN"1"29;
%"Q_RES"
"1","(-1075,5425)","0","pure_quanta","I3";
;
LOCATION"R9034"
$SEC"1"
CDS_SEC"1"
VALUE"33.2"
MATERIAL"CHIP"
PACK_TYPE"0402LF"
WATTAGE"1/16W"
TOLERANCE"1%"
CDS_LIB"pure_quanta"
PART_NUMBER"CS03322FB03";
"B"
$PN"2"24;
"A"
$PN"1"21;
%"MOSFET_N"
"1","(-3925,8950)","0","pure_quanta","I31";
;
LOCATION"U24"
$SEC"1"
CDS_SEC"1"
MATERIAL"IC"
VALUE"BSS138K"
MANUF_PN"BSS138K"
PACK_TYPE"SMLF"
CDS_LIB"pure_quanta"
CDS_LMAN_SYM_OUTLINE"-50,50,100,-150"
PART_NUMBER"BAM138K0000";
"GATE"
$PN"G"37;
"SOURCE"
$PN"S"5;
"DRAIN"
$PN"D"36;
%"UNIVERSAL_GND"
"1","(-3875,8400)","0","pure_quanta_power","I32";
;
CDS_LIB"pure_quanta_power"
HDL_POWER"GND";
"A"5;
%"Q_RES"
"2","(-3875,9500)","2","pure_quanta","I34";
;
LOCATION"R1128"
$SEC"1"
CDS_SEC"1"
TOLERANCE"1%"
VALUE"1K"
WATTAGE"1/16W"
MATERIAL"CHIP"
PACK_TYPE"0402LF"
CDS_LIB"pure_quanta"
PART_NUMBER"CS21002FB06";
"A"
$PN"1"6;
"B"
$PN"2"36;
%"UNIVERSAL_POWER"
"1","(-3875,9900)","2","pure_quanta_power","I35";
;
HDL_POWER"P3V3_AUX"
CDS_LIB"pure_quanta_power";
"A"6;
%"74LVC1G08W57"
"1","(-750,9200)","0","pure_quanta","I36";
;
LOCATION"U23"
SEC"1"
MATERIAL"IC"
VALUE"74LVC1G08W5-7"
PART_TYPE"SMLF"
NEEDS_NO_SIZE"TRUE"
CDS_LMAN_SYM_OUTLINE"-150,150,150,-150"
CDS_LIB"pure_quanta"
SEC_TYPE""
PART_NUMBER"AL1G0008020";
"VCC"
$PN"5"50;
"Y"
$PN"4"42;
"GND"
$PN"3"49;
"B"
$PN"2"36;
"A"
$PN"1"60;
%"UNIVERSAL_GND"
"1","(-1325,8825)","0","pure_quanta_power","I37";
;
CDS_LIB"pure_quanta_power"
HDL_POWER"GND";
"A"49;
%"UNIVERSAL_POWER"
"1","(-150,9825)","2","pure_quanta_power","I39";
;
HDL_POWER"P3V3_AUX"
CDS_LIB"pure_quanta_power";
"A"50;
%"UNIVERSAL_POWER"
"1","(-1625,5975)","2","pure_quanta_power","I4";
;
HDL_POWER"P3V3_AUX"
CDS_LIB"pure_quanta_power";
"A"7;
%"Q_CAP"
"1","(-150,9550)","0","pure_quanta","I40";
;
LOCATION"C1059"
$SEC"1"
CDS_SEC"1"
VOLTAGE"25V"
PACK_TYPE"0402"
VALUE"0.1UF"
MATERIAL"X7R"
TOLERANCE"10%"
CDS_LIB"pure_quanta"
PART_NUMBER"CH4104K1B00";
"B"
$PN"2"8;
"A"
$PN"1"50;
%"UNIVERSAL_GND"
"1","(-150,9250)","0","pure_quanta_power","I41";
;
CDS_LIB"pure_quanta_power"
HDL_POWER"GND";
"A"8;
%"UNIVERSAL_POWER"
"1","(-1225,10125)","2","pure_quanta_power","I43";
;
HDL_POWER"P3V3_AUX"
CDS_LIB"pure_quanta_power";
"A"9;
%"Q_RES"
"2","(-1225,9725)","2","pure_quanta","I44";
;
LOCATION"R1131"
$SEC"1"
CDS_SEC"1"
VALUE"1K"
PACK_TYPE"0402LF"
WATTAGE"1/16W"
MATERIAL"CHIP"
TOLERANCE"1%"
CDS_LIB"pure_quanta"
PART_NUMBER"CS21002FB06";
"A"
$PN"1"9;
"B"
$PN"2"60;
%"Q_RES"
"1","(650,9150)","0","pure_quanta","I47";
;
LOCATION"R1134"
$SEC"1"
CDS_SEC"1"
WATTAGE"1/16W"
MATERIAL"CHIP"
TOLERANCE"5%"
VALUE"0"
PACK_TYPE"0402LF"
CDS_LIB"pure_quanta"
PART_NUMBER"CS00002JB13";
"B"
$PN"2"41;
"A"
$PN"1"42;
%"Q_RES"
"1","(-2125,9300)","0","pure_quanta","I49";
;
LOCATION"R1130"
$SEC"1"
CDS_SEC"1"
MATERIAL"EMPTY"
TOLERANCE"5%"
VALUE"0"
WATTAGE"1/16W"
PACK_TYPE"0402LF"
CDS_LIB"pure_quanta"
PART_NUMBER"CS00002JB13";
"B"
$PN"2"60;
"A"
$PN"1"35;
%"SN74LVC1G07DBVR"
"1","(-2375,7450)","0","pure_quanta","I51";
;
LOCATION"U28"
$SEC"1"
CDS_SEC"1"
PACK_TYPE"SMLF"
MATERIAL"IC"
VALUE"SN74LVC1G07DBVR"
NEEDS_NO_SIZE"TRUE"
CDS_LIB"pure_quanta"
PART_NUMBER"AL1G0007024";
"NC"
$PN"1"0;
"Y"
$PN"4"59;
"GND"
$PN"3"52;
"A"
$PN"2"58;
"VCC"
$PN"5"51;
%"UNIVERSAL_POWER"
"1","(-3075,8200)","2","pure_quanta_power","I52";
;
HDL_POWER"P3V3_AUX"
CDS_LIB"pure_quanta_power";
"A"51;
%"Q_CAP"
"1","(-3100,7875)","2","pure_quanta","I53";
;
LOCATION"C1058"
$SEC"1"
CDS_SEC"1"
MATERIAL"X7R"
TOLERANCE"10%"
VOLTAGE"25V"
PACK_TYPE"0402"
VALUE"0.1UF"
CDS_LIB"pure_quanta"
PART_NUMBER"CH4104K1B00";
"B"
$PN"2"10;
"A"
$PN"1"51;
%"UNIVERSAL_GND"
"1","(-3100,7650)","0","pure_quanta_power","I54";
;
CDS_LIB"pure_quanta_power"
HDL_POWER"GND";
"A"10;
%"UNIVERSAL_GND"
"1","(-2950,7250)","0","pure_quanta_power","I55";
;
CDS_LIB"pure_quanta_power"
HDL_POWER"GND";
"A"52;
%"Q_RES"
"1","(-3800,7450)","0","pure_quanta","I57";
;
LOCATION"R1129"
$SEC"1"
CDS_SEC"1"
TOLERANCE"5%"
WATTAGE"1/16W"
PACK_TYPE"0402LF"
VALUE"0"
MATERIAL"CHIP"
CDS_LIB"pure_quanta"
PART_NUMBER"CS00002JB13";
"B"
$PN"2"58;
"A"
$PN"1"39;
%"Q_RES"
"1","(-1325,7450)","0","pure_quanta","I58";
;
LOCATION"R1132"
$SEC"1"
CDS_SEC"1"
WATTAGE"1/16W"
VALUE"0"
PACK_TYPE"0402LF"
TOLERANCE"5%"
MATERIAL"CHIP"
CDS_LIB"pure_quanta"
PART_NUMBER"CS00002JB13";
"B"
$PN"2"57;
"A"
$PN"1"59;
%"UNIVERSAL_POWER"
"1","(-875,8050)","2","pure_quanta_power","I60";
;
HDL_POWER"P3V3_AUX"
CDS_LIB"pure_quanta_power";
"A"11;
%"Q_RES"
"2","(-875,7800)","2","pure_quanta","I61";
;
LOCATION"R1133"
$SEC"1"
CDS_SEC"1"
VALUE"1K"
TOLERANCE"1%"
MATERIAL"CHIP"
WATTAGE"1/16W"
PACK_TYPE"0402LF"
CDS_LIB"pure_quanta"
PART_NUMBER"CS21002FB06";
"A"
$PN"1"11;
"B"
$PN"2"57;
%"UNIVERSAL_POWER"
"1","(2475,8825)","2","pure_quanta_power","I63";
;
HDL_POWER"P3V3_AUX"
CDS_LIB"pure_quanta_power";
"A"12;
%"Q_RES"
"2","(2475,8575)","2","pure_quanta","I64";
;
LOCATION"R1144"
$SEC"1"
CDS_SEC"1"
VALUE"1K"
TOLERANCE"1%"
MATERIAL"CHIP"
WATTAGE"1/16W"
PACK_TYPE"0402LF"
CDS_LIB"pure_quanta"
PART_NUMBER"CS21002FB06";
"A"
$PN"1"12;
"B"
$PN"2"44;
%"Q_RES"
"1","(1975,8225)","0","pure_quanta","I65";
;
LOCATION"R1143"
$SEC"1"
CDS_SEC"1"
MATERIAL"CHIP"
VALUE"0"
TOLERANCE"5%"
WATTAGE"1/16W"
PACK_TYPE"0402LF"
CDS_LIB"pure_quanta"
PART_NUMBER"CS00002JB13";
"B"
$PN"2"44;
"A"
$PN"1"43;
%"SN74LVC1G07DBVR"
"1","(900,8225)","0","pure_quanta","I66";
;
LOCATION"U30"
$SEC"1"
CDS_SEC"1"
VALUE"SN74LVC1G07DBVR"
PACK_TYPE"SMLF"
MATERIAL"IC"
NEEDS_NO_SIZE"TRUE"
CDS_LIB"pure_quanta"
PART_NUMBER"AL1G0007024";
"NC"
$PN"1"0;
"Y"
$PN"4"43;
"GND"
$PN"3"53;
"A"
$PN"2"46;
"VCC"
$PN"5"54;
%"UNIVERSAL_GND"
"1","(325,8025)","0","pure_quanta_power","I67";
;
CDS_LIB"pure_quanta_power"
HDL_POWER"GND";
"A"53;
%"UNIVERSAL_POWER"
"1","(200,8975)","2","pure_quanta_power","I68";
;
HDL_POWER"P3V3_AUX"
CDS_LIB"pure_quanta_power";
"A"54;
%"Q_CAP"
"1","(175,8650)","2","pure_quanta","I69";
;
LOCATION"C1060"
$SEC"1"
CDS_SEC"1"
TOLERANCE"10%"
PACK_TYPE"0402"
VOLTAGE"25V"
MATERIAL"X7R"
VALUE"0.1UF"
CDS_LIB"pure_quanta"
PART_NUMBER"CH4104K1B00";
"B"
$PN"2"13;
"A"
$PN"1"54;
%"UNIVERSAL_GND"
"1","(175,8425)","0","pure_quanta_power","I70";
;
CDS_LIB"pure_quanta_power"
HDL_POWER"GND";
"A"13;
%"Q_RES"
"1","(-450,8225)","0","pure_quanta","I71";
;
LOCATION"R1142"
$SEC"1"
CDS_SEC"1"
WATTAGE"1/16W"
MATERIAL"CHIP"
PACK_TYPE"0402LF"
VALUE"0"
TOLERANCE"5%"
CDS_LIB"pure_quanta"
PART_NUMBER"CS00002JB13";
"B"
$PN"2"46;
"A"
$PN"1"33;
%"74LVC1G32GW"
"1","(425,5375)","0","pure_quanta","I74";
;
LOCATION"U9002"
$SEC"1"
CDS_SEC"1"
VALUE"74LVC1G32GW"
PACK_TYPE"SMLF"
MATERIAL"IC"
CDS_LIB"pure_quanta"
NEEDS_NO_SIZE"TRUE"
PART_NUMBER"ALVC1G32007";
"GND"
$PN"3"1;
"O"
$PN"4"22;
"I1"
$PN"2"23;
"VCC"
$PN"5"27;
"I0"
$PN"1"24;
%"Q_CAP"
"1","(-50,5700)","2","pure_quanta","I75";
;
LOCATION"C9008"
$SEC"1"
CDS_SEC"1"
MATERIAL"X7R"
VOLTAGE"25V"
TOLERANCE"10%"
VALUE"0.1UF"
PACK_TYPE"0402"
CDS_LIB"pure_quanta"
PART_NUMBER"CH4104K1B00";
"B"
$PN"2"2;
"A"
$PN"1"27;
%"Q_RES"
"2","(2700,5850)","0","pure_quanta","I76";
;
LOCATION"R1145"
$SEC"1"
CDS_SEC"1"
VALUE"10K"
PACK_TYPE"0402LF"
MATERIAL"EMPTY"
WATTAGE"1/16W"
TOLERANCE"5%"
CDS_LIB"pure_quanta"
PART_NUMBER"CS31002JB08";
"A"
$PN"1"14;
"B"
$PN"2"45;
%"UNIVERSAL_POWER"
"1","(2700,6100)","2","pure_quanta_power","I77";
;
HDL_POWER"P3V3_AUX"
CDS_LIB"pure_quanta_power";
"A"14;
%"UNIVERSAL_GND"
"1","(-4825,4100)","0","pure_quanta_power","I78";
;
CDS_LIB"pure_quanta_power"
HDL_POWER"GND";
"A"15;
%"Q_CAP"
"1","(-4825,4425)","2","pure_quanta","I79";
;
LOCATION"C8008"
$SEC"1"
CDS_SEC"1"
MATERIAL"X7R"
TOLERANCE"10%"
PACK_TYPE"0402"
VOLTAGE"25V"
VALUE"0.1UF"
CDS_LIB"pure_quanta"
PART_NUMBER"CH4104K1B00";
"B"
$PN"2"15;
"A"
$PN"1"55;
%"APX80929SAG7"
"1","(-4250,4675)","2","pure_quanta","I80";
;
LOCATION"U8001"
SEC"1"
MATERIAL"IC"
VALUE"APX809-29SAG-7"
PART_TYPE"SMLF"
CDS_LMAN_SYM_OUTLINE"-225,200,225,-200"
NEEDS_NO_SIZE"TRUE"
CDS_LIB"pure_quanta"
SEC_TYPE""
PART_NUMBER"AL080929000";
"GND"
$PN"1"16;
"RESET_L \B"
$PN"2"47;
"VCC"
$PN"3"55;
%"UNIVERSAL_POWER"
"1","(-4825,4950)","2","pure_quanta_power","I81";
;
HDL_POWER"P3V3_OCP_SFF_R"
CDS_LIB"pure_quanta_power";
"A"55;
%"UNIVERSAL_GND"
"1","(-3700,4675)","0","pure_quanta_power","I82";
;
CDS_LIB"pure_quanta_power"
HDL_POWER"GND";
"A"16;
%"UNIVERSAL_GND"
"1","(-3175,4025)","0","pure_quanta_power","I83";
;
CDS_LIB"pure_quanta_power"
HDL_POWER"GND";
"A"17;
%"Q_RES"
"2","(-3175,4300)","0","pure_quanta","I84";
;
LOCATION"R8093"
$SEC"1"
CDS_SEC"1"
VALUE"100K"
TOLERANCE"1%"
PACK_TYPE"0402LF"
MATERIAL"CHIP"
WATTAGE"1/16W"
CDS_LIB"pure_quanta"
PART_NUMBER"CS41002FB09";
"A"
$PN"1"47;
"B"
$PN"2"17;
%"Q_RES"
"1","(-2650,4575)","0","pure_quanta","I85";
;
LOCATION"R8094"
SEC"1"
PACK_TYPE"0402LF"
VALUE"0"
MATERIAL"CHIP"
WATTAGE"1/16W"
TOLERANCE"5%"
CDS_LIB"pure_quanta"
SEC_TYPE"0402LF"
PART_NUMBER"CS00002JB13";
"B"
$PN"2"25;
"A"
$PN"1"47;
%"UNIVERSAL_POWER"
"1","(-3175,5150)","2","pure_quanta_power","I87";
;
HDL_POWER"P3V3_OCP_SFF_R"
CDS_LIB"pure_quanta_power";
"A"18;
%"Q_RES"
"2","(-3175,4900)","2","pure_quanta","I90";
;
LOCATION"R8092"
$SEC"1"
CDS_SEC"1"
VALUE"10K"
PACK_TYPE"0402LF"
WATTAGE"1/16W"
MATERIAL"EMPTY"
TOLERANCE"5%"
CDS_LIB"pure_quanta"
PART_NUMBER"CS31002JB08";
"A"
$PN"1"18;
"B"
$PN"2"47;
%"74LVC1G08W57"
"1","(-3900,6375)","0","pure_quanta","I91";
;
LOCATION"U9050"
$SEC"1"
CDS_SEC"1"
MATERIAL"IC"
PART_TYPE"SMLF"
VALUE"74LVC1G08W5-7"
CDS_LIB"pure_quanta"
CDS_LMAN_SYM_OUTLINE"-150,150,150,-150"
NEEDS_NO_SIZE"TRUE"
PART_NUMBER"AL1G0008020";
"VCC"
$PN"5"56;
"Y"
$PN"4"31;
"GND"
$PN"3"19;
"B"
$PN"2"62;
"A"
$PN"1"34;
%"UNIVERSAL_GND"
"1","(-4250,6050)","0","pure_quanta_power","I92";
;
CDS_LIB"pure_quanta_power"
HDL_POWER"GND";
"A"19;
%"UNIVERSAL_POWER"
"1","(-3475,6875)","2","pure_quanta_power","I93";
;
HDL_POWER"P3V3_AUX"
CDS_LIB"pure_quanta_power";
"A"56;
%"Q_CAP"
"1","(-3475,6575)","0","pure_quanta","I94";
;
LOCATION"C9050"
$SEC"1"
CDS_SEC"1"
TOLERANCE"10%"
MATERIAL"X7R"
PACK_TYPE"0402"
VALUE"0.1UF"
VOLTAGE"25V"
CDS_LIB"pure_quanta"
PART_NUMBER"CH4104K1B00";
"B"
$PN"2"20;
"A"
$PN"1"56;
%"UNIVERSAL_GND"
"1","(-3475,6375)","0","pure_quanta_power","I95";
;
CDS_LIB"pure_quanta_power"
HDL_POWER"GND";
"A"20;
%"Q_RES"
"1","(-3975,5925)","0","pure_quanta","I96";
;
LOCATION"R1509"
$SEC"1"
CDS_SEC"1"
TOLERANCE"5%"
VALUE"0"
PACK_TYPE"0402LF"
WATTAGE"1/16W"
MATERIAL"CHIP"
CDS_LIB"pure_quanta"
PART_NUMBER"CS00002JB13";
"B"
$PN"2"38;
"A"
$PN"1"61;
END.
